(kicad_pcb
	(version 20260206)
	(generator "pcbnew")
	(generator_version "10.0")
	(general
		(thickness 1.6)
		(legacy_teardrops no)
	)
	(paper "A4")
	(title_block
		(title "netronome-mezz — pcbd0082-001_rev01_jul9_a.brd")
		(comment 1 "Open CloudServer (Microsoft) / footprints 698-701 of 714")
	)
	(layers
		(0 "F.Cu" signal "TOP")
		(4 "In1.Cu" signal "02_GND")
		(6 "In2.Cu" signal "03_SIG")
		(8 "In3.Cu" signal "04_SIG")
		(10 "In4.Cu" signal "05_GND")
		(12 "In5.Cu" signal "06_PWR1")
		(14 "In6.Cu" signal "07_SIG")
		(16 "In7.Cu" signal "08_SIG")
		(18 "In8.Cu" signal "09_GND")
		(2 "B.Cu" signal "BOTTOM")
		(9 "F.Adhes" user "F.Adhesive")
		(11 "B.Adhes" user "B.Adhesive")
		(13 "F.Paste" user "Package Geometry/Pastemask Top")
		(15 "B.Paste" user "Package Geometry/Pastemask Bottom")
		(5 "F.SilkS" user "Ref Des/Silkscreen Top")
		(7 "B.SilkS" user "Ref Des/Silkscreen Bottom")
		(1 "F.Mask" user "Board Geometry/Soldermask Top")
		(3 "B.Mask" user "Board Geometry/Soldermask Bottom")
		(17 "Dwgs.User" user "User.Drawings")
		(19 "Cmts.User" user "User.Comments")
		(21 "Eco1.User" user "User.Eco1")
		(23 "Eco2.User" user "User.Eco2")
		(25 "Edge.Cuts" user "Board Geometry/Outline")
		(27 "Margin" user)
		(31 "F.CrtYd" user "Package Geometry/Place Bound Top")
		(29 "B.CrtYd" user "Package Geometry/Place Bound Bottom")
		(35 "F.Fab" user "Ref Des/Assembly Top")
		(33 "B.Fab" user "Ref Des/Assembly Bottom")
		(45 "User.4" user "COMPVAL_TYPE_BOTTOM")
	)
	(footprint ""
		(layer "B.Cu")
		(at 20.32 13.589 180)
		(property "Reference" "R18"
			(at 1.16967 -0.635 270)
			(unlocked yes)
			(layer "B.SilkS")
			(effects
				(font
					(size 0.7874 0.5842)
					(thickness 0.127)
				)
				(justify left mirror)
			)
		)
		(property "Value" "4.75K"
			(at 0.148158 1.3462 90)
			(unlocked yes)
			(layer "B.Fab")
			(hide yes)
			(effects
				(font
					(size 1.27 0.9652)
					(thickness 0.000001)
				)
				(justify left mirror)
			)
		)
		(property "Device Type" "REST4024"
			(at 0.148158 1.3462 90)
			(unlocked yes)
			(layer "B.Fab")
			(hide yes)
			(effects
				(font
					(size 1.27 0.9652)
					(thickness 0.000001)
				)
				(justify left mirror)
			)
		)
		(duplicate_pad_numbers_are_jumpers no)
		(fp_poly
			(pts
				(xy -0.635 1.0668) (xy -0.635 -1.0668) (xy 0.635 -1.0668) (xy 0.635 1.0668)
			)
			(stroke
				(width 0)
				(type default)
			)
			(fill no)
			(layer "B.CrtYd")
		)
		(fp_line
			(start 0.254 0.508)
			(end 0.254 -0.508)
			(stroke
				(width 0.0254)
				(type default)
			)
			(layer "B.Fab")
		)
		(fp_line
			(start 0.254 -0.508)
			(end -0.254 -0.508)
			(stroke
				(width 0.0254)
				(type default)
			)
			(layer "B.Fab")
		)
		(fp_line
			(start -0.254 0.508)
			(end 0.254 0.508)
			(stroke
				(width 0.0254)
				(type default)
			)
			(layer "B.Fab")
		)
		(fp_line
			(start -0.254 -0.508)
			(end -0.254 0.508)
			(stroke
				(width 0.0254)
				(type default)
			)
			(layer "B.Fab")
		)
		(pad "1" smd rect
			(at 0 -0.4191)
			(size 0.508 0.5334)
			(layers "B.Cu" "B.Mask" "B.Paste")
			(net "NFP_CFG_SPI_FLASH_SEL")
		)
		(pad "2" smd rect
			(at 0 0.4191)
			(size 0.508 0.5334)
			(layers "B.Cu" "B.Mask" "B.Paste")
			(net "GND")
		)
		(zone
			(layer "B.Cu")
			(hatch none 0.5)
			(connect_pads
				(clearance 0)
			)
			(min_thickness 0.25)
			(keepout
				(tracks not_allowed)
				(vias allowed)
				(pads allowed)
				(copperpour not_allowed)
				(footprints allowed)
			)
			(placement
				(enabled no)
				(sheetname "")
			)
			(fill
				(thermal_gap 0.5)
				(thermal_bridge_width 0.5)
				(island_removal_mode 0)
			)
			(polygon
				(pts
					(xy 20.3454 13.6144) (xy 20.3454 13.5636) (xy 20.2946 13.5636) (xy 20.2946 13.6144)
				)
			)
		)
	)
	(footprint ""
		(layer "B.Cu")
		(at 48.237013 8.54202 180)
		(property "Reference" "C40"
			(at 0 0 0)
			(layer "B.SilkS")
			(hide yes)
			(effects
				(font
					(size 1.27 1.27)
				)
				(justify mirror)
			)
		)
		(property "Value" ""
			(at 0 0 0)
			(layer "B.Fab")
			(effects
				(font
					(size 1.27 1.27)
				)
				(justify mirror)
			)
		)
		(duplicate_pad_numbers_are_jumpers no)
		(fp_circle
			(center 0 0)
			(end -0.104648 0)
			(stroke
				(width 0.1016)
				(type default)
			)
			(fill no)
			(layer "B.SilkS")
		)
		(fp_poly
			(pts
				(xy 0.381 -0.889) (xy 0.381 0.889) (xy -0.381 0.889) (xy -0.381 -0.889)
			)
			(stroke
				(width 0)
				(type default)
			)
			(fill no)
			(layer "B.CrtYd")
		)
		(fp_line
			(start 0.508 1.016)
			(end 0.508 -1.016)
			(stroke
				(width 0.0254)
				(type default)
			)
			(layer "B.Fab")
		)
		(fp_line
			(start 0.508 -1.016)
			(end 0.254 -1.016)
			(stroke
				(width 0.0254)
				(type default)
			)
			(layer "B.Fab")
		)
		(fp_line
			(start 0.254 -1.016)
			(end -0.508 -1.016)
			(stroke
				(width 0.0254)
				(type default)
			)
			(layer "B.Fab")
		)
		(fp_line
			(start -0.508 1.016)
			(end 0.508 1.016)
			(stroke
				(width 0.0254)
				(type default)
			)
			(layer "B.Fab")
		)
		(fp_line
			(start -0.508 -1.016)
			(end -0.508 1.016)
			(stroke
				(width 0.0254)
				(type default)
			)
			(layer "B.Fab")
		)
		(pad "1" smd custom
			(at 0 -0.500126)
			(size 0.127 0.127)
			(layers "B.Cu" "B.Mask" "B.Paste")
			(net "VDDA_SERDES")
			(options
				(clearance outline)
				(anchor circle)
			)
			(primitives
				(gr_poly
					(pts
						(xy -0.1778 0.254) (xy 0.1778 0.254) (xy 0.254 0.1778) (xy 0.254 -0.1778) (xy 0.1778 -0.254) (xy -0.1778 -0.254)
						(xy -0.254 -0.1778) (xy -0.254 0.1778)
					)
					(width 0)
					(fill yes)
				)
			)
		)
		(pad "2" smd custom
			(at 0 0.500126)
			(size 0.127 0.127)
			(layers "B.Cu" "B.Mask" "B.Paste")
			(net "GND")
			(options
				(clearance outline)
				(anchor circle)
			)
			(primitives
				(gr_poly
					(pts
						(xy -0.1778 0.254) (xy 0.1778 0.254) (xy 0.254 0.1778) (xy 0.254 -0.1778) (xy 0.1778 -0.254) (xy -0.1778 -0.254)
						(xy -0.254 -0.1778) (xy -0.254 0.1778)
					)
					(width 0)
					(fill yes)
				)
			)
		)
	)
	(footprint ""
		(layer "B.Cu")
		(at 64.236981 13.54201 180)
		(property "Reference" "C194"
			(at 0 0 0)
			(layer "B.SilkS")
			(hide yes)
			(effects
				(font
					(size 1.27 1.27)
				)
				(justify mirror)
			)
		)
		(property "Value" ""
			(at 0 0 0)
			(layer "B.Fab")
			(effects
				(font
					(size 1.27 1.27)
				)
				(justify mirror)
			)
		)
		(duplicate_pad_numbers_are_jumpers no)
		(fp_circle
			(center 0 0)
			(end -0.104648 0)
			(stroke
				(width 0.1016)
				(type default)
			)
			(fill no)
			(layer "B.SilkS")
		)
		(fp_poly
			(pts
				(xy 0.381 -0.889) (xy 0.381 0.889) (xy -0.381 0.889) (xy -0.381 -0.889)
			)
			(stroke
				(width 0)
				(type default)
			)
			(fill no)
			(layer "B.CrtYd")
		)
		(fp_line
			(start 0.508 1.016)
			(end 0.508 -1.016)
			(stroke
				(width 0.0254)
				(type default)
			)
			(layer "B.Fab")
		)
		(fp_line
			(start 0.508 -1.016)
			(end 0.254 -1.016)
			(stroke
				(width 0.0254)
				(type default)
			)
			(layer "B.Fab")
		)
		(fp_line
			(start 0.254 -1.016)
			(end -0.508 -1.016)
			(stroke
				(width 0.0254)
				(type default)
			)
			(layer "B.Fab")
		)
		(fp_line
			(start -0.508 1.016)
			(end 0.508 1.016)
			(stroke
				(width 0.0254)
				(type default)
			)
			(layer "B.Fab")
		)
		(fp_line
			(start -0.508 -1.016)
			(end -0.508 1.016)
			(stroke
				(width 0.0254)
				(type default)
			)
			(layer "B.Fab")
		)
		(pad "1" smd custom
			(at 0 -0.500126)
			(size 0.127 0.127)
			(layers "B.Cu" "B.Mask" "B.Paste")
			(net "DDR_VDDQ")
			(options
				(clearance outline)
				(anchor circle)
			)
			(primitives
				(gr_poly
					(pts
						(xy -0.1778 0.254) (xy 0.1778 0.254) (xy 0.254 0.1778) (xy 0.254 -0.1778) (xy 0.1778 -0.254) (xy -0.1778 -0.254)
						(xy -0.254 -0.1778) (xy -0.254 0.1778)
					)
					(width 0)
					(fill yes)
				)
			)
		)
		(pad "2" smd custom
			(at 0 0.500126)
			(size 0.127 0.127)
			(layers "B.Cu" "B.Mask" "B.Paste")
			(net "GND")
			(options
				(clearance outline)
				(anchor circle)
			)
			(primitives
				(gr_poly
					(pts
						(xy -0.1778 0.254) (xy 0.1778 0.254) (xy 0.254 0.1778) (xy 0.254 -0.1778) (xy 0.1778 -0.254) (xy -0.1778 -0.254)
						(xy -0.254 -0.1778) (xy -0.254 0.1778)
					)
					(width 0)
					(fill yes)
				)
			)
		)
	)
	(footprint ""
		(layer "B.Cu")
		(at 61.236987 33.54197)
		(property "Reference" "C80"
			(at 0.966343 -1.53797 270)
			(unlocked yes)
			(layer "B.SilkS")
			(effects
				(font
					(size 0.7874 0.5842)
					(thickness 0.127)
				)
				(justify mirror)
			)
		)
		(property "Value" ""
			(at 0 0 0)
			(layer "B.Fab")
			(effects
				(font
					(size 1.27 1.27)
				)
				(justify mirror)
			)
		)
		(duplicate_pad_numbers_are_jumpers no)
		(fp_circle
			(center 0 0)
			(end 0.104648 0)
			(stroke
				(width 0.1016)
				(type default)
			)
			(fill no)
			(layer "B.SilkS")
		)
		(fp_poly
			(pts
				(xy 0.381 -0.889) (xy 0.381 0.889) (xy -0.381 0.889) (xy -0.381 -0.889)
			)
			(stroke
				(width 0)
				(type default)
			)
			(fill no)
			(layer "B.CrtYd")
		)
		(fp_line
			(start -0.508 -1.016)
			(end -0.508 1.016)
			(stroke
				(width 0.0254)
				(type default)
			)
			(layer "B.Fab")
		)
		(fp_line
			(start -0.508 1.016)
			(end 0.508 1.016)
			(stroke
				(width 0.0254)
				(type default)
			)
			(layer "B.Fab")
		)
		(fp_line
			(start 0.254 -1.016)
			(end -0.508 -1.016)
			(stroke
				(width 0.0254)
				(type default)
			)
			(layer "B.Fab")
		)
		(fp_line
			(start 0.508 -1.016)
			(end 0.254 -1.016)
			(stroke
				(width 0.0254)
				(type default)
			)
			(layer "B.Fab")
		)
		(fp_line
			(start 0.508 1.016)
			(end 0.508 -1.016)
			(stroke
				(width 0.0254)
				(type default)
			)
			(layer "B.Fab")
		)
		(pad "1" smd custom
			(at 0 -0.500126 180)
			(size 0.127 0.127)
			(layers "B.Cu" "B.Mask" "B.Paste")
			(net "VDD_CORE")
			(options
				(clearance outline)
				(anchor circle)
			)
			(primitives
				(gr_poly
					(pts
						(xy -0.1778 0.254) (xy 0.1778 0.254) (xy 0.254 0.1778) (xy 0.254 -0.1778) (xy 0.1778 -0.254) (xy -0.1778 -0.254)
						(xy -0.254 -0.1778) (xy -0.254 0.1778)
					)
					(width 0)
					(fill yes)
				)
			)
		)
		(pad "2" smd custom
			(at 0 0.500126 180)
			(size 0.127 0.127)
			(layers "B.Cu" "B.Mask" "B.Paste")
			(net "GND")
			(options
				(clearance outline)
				(anchor circle)
			)
			(primitives
				(gr_poly
					(pts
						(xy -0.1778 0.254) (xy 0.1778 0.254) (xy 0.254 0.1778) (xy 0.254 -0.1778) (xy 0.1778 -0.254) (xy -0.1778 -0.254)
						(xy -0.254 -0.1778) (xy -0.254 0.1778)
					)
					(width 0)
					(fill yes)
				)
			)
		)
	)
)
